# T6G (Grand Teton) — schematic netlist excerpt (pin names and nets, part order shuffled) for the footprints in the layout excerpt that follows; sources: Cadence DE-HDL packaged netlist, KiCad conversion of 04192023_DAF0TMB3IC0_F0TG_MB_C_brd_V02_OCP.brd

J17  SCONN288_DDR506112002KQ  IO  pkg DDR288S_1-1VXC  page 88
  VIN_BULK0  = P12V_MEM_CPU0
  RFU0  = NC
  VIN_MGMT  = P3V3_AUX
  HSCL  = I3C_SPD_DDRC_CPU0_SCL
  HSDA  = I3C_SPD_DDRC_CPU0_SDA
  VSS0  = GND
  DQ0_A  = M_C_CPU0_SA_DQ<0>
  VSS1  = GND
  DQ1_A  = M_C_CPU0_SA_DQ<1>
  VSS2  = GND
  DQS0_A_T  = M_C_CPU0_SA_DQS_DP<0>
  DQS0_A_C  = M_C_CPU0_SA_DQS_DN<0>
  VSS3  = GND
  DQ4_A  = M_C_CPU0_SA_DQ<4>
  VSS4  = GND
  DQ5_A  = M_C_CPU0_SA_DQ<5>
  VSS5  = GND
  DQ8_A  = M_C_CPU0_SA_DQ<8>
  VSS6  = GND
  DQ9_A  = M_C_CPU0_SA_DQ<9>
  VSS7  = GND
  DQS1_A_T  = M_C_CPU0_SA_DQS_DP<1>
  DQS1_A_C  = M_C_CPU0_SA_DQS_DN<1>
  VSS8  = GND
  DQ12_A  = M_C_CPU0_SA_DQ<12>
  VSS9  = GND
  DQ13_A  = M_C_CPU0_SA_DQ<13>
  VSS10  = GND
  DQ16_A  = M_C_CPU0_SA_DQ<16>
  VSS11  = GND
  DQ17_A  = M_C_CPU0_SA_DQ<17>
  VSS12  = GND
  DQS2_A_T  = M_C_CPU0_SA_DQS_DP<2>
  DQS2_A_C  = M_C_CPU0_SA_DQS_DN<2>
  VSS13  = GND
  DQ20_A  = M_C_CPU0_SA_DQ<20>
  VSS14  = GND
  DQ21_A  = M_C_CPU0_SA_DQ<21>
  VSS15  = GND
  DQ24_A  = M_C_CPU0_SA_DQ<24>
  VSS16  = GND
  DQ25_A  = M_C_CPU0_SA_DQ<25>
  VSS17  = GND
  DQS3_A_T  = M_C_CPU0_SA_DQS_DP<3>
  DQS3_A_C  = M_C_CPU0_SA_DQS_DN<3>
  VSS18  = GND
  DQ28_A  = M_C_CPU0_SA_DQ<28>
  VSS19  = GND
  DQ29_A  = M_C_CPU0_SA_DQ<29>
  VSS20  = GND
  CB0_A  = M_C_CPU0_SA_CB<0>
  VSS21  = GND
  CB1_A  = M_C_CPU0_SA_CB<1>
  VSS22  = GND
  DQS4_A_T  = M_C_CPU0_SA_DQS_DP<4>
  DQS4_A_C  = M_C_CPU0_SA_DQS_DN<4>
  VSS23  = GND
  CB4_A  = M_C_CPU0_SA_CB<4>
  VSS24  = GND
  CB5_A  = M_C_CPU0_SA_CB<5>
  VSS25  = GND
  ALERT_N  = M_C_CPU0_ALERT_N
  VSS26  = GND
  CS0_A_N  = M_C_CPU0_SA_CS_N<0>
  VSS27  = GND
  CA0_A  = M_C_CPU0_SA_CA<0>
  VSS28  = GND
  CA2_A  = M_C_CPU0_SA_CA<2>
  VSS29  = GND
  CA4_A  = M_C_CPU0_SA_CA<4>
  VSS30  = GND
  CA6_A  = M_C_CPU0_SA_CA<6>
  VSS31  = GND
  PAR_A  = M_C_CPU0_SA_PAR
  VSS32  = GND
  CA0_B  = M_C_CPU0_SB_CA<0>
  VSS33  = GND
  CA2_B  = M_C_CPU0_SB_CA<2>
  VSS34  = GND
  CA4_B  = M_C_CPU0_SB_CA<4>
  VSS35  = GND
  CA6_B  = M_C_CPU0_SB_CA<6>
  VSS36  = GND
  CS0_B_N  = M_C_CPU0_SB_CS_N<0>
  VSS37  = GND
  \lbd||rsp_a_n\  = M_C_CPU0_SA_RSP<0>
  \lbs||rsp_b_n\  = M_C_CPU0_SB_RSP<0>
  VSS38  = GND
  CB4_B  = M_C_CPU0_SB_CB<4>
  VSS39  = GND
  CB5_B  = M_C_CPU0_SB_CB<5>
  VSS40  = GND
  \dqs9_b_t||tdqs9_b_t||dbi4_b_n\  = M_C_CPU0_SB_DQS_DP<9>
  \dqs9_b_c||tdqs9_b_c\  = M_C_CPU0_SB_DQS_DN<9>
  VSS41  = GND
  CB0_B  = M_C_CPU0_SB_CB<0>
  VSS42  = GND
  CB1_B  = M_C_CPU0_SB_CB<1>
  VSS43  = GND
  DQ0_B  = M_C_CPU0_SB_DQ<0>
  VSS44  = GND
  DQ1_B  = M_C_CPU0_SB_DQ<1>
  VSS45  = GND
  DQS0_B_T  = M_C_CPU0_SB_DQS_DP<0>
  DQS0_B_C  = M_C_CPU0_SB_DQS_DN<0>
  VSS46  = GND
  DQ4_B  = M_C_CPU0_SB_DQ<4>
  VSS47  = GND
  DQ5_B  = M_C_CPU0_SB_DQ<5>
  VSS48  = GND
  DQ8_B  = M_C_CPU0_SB_DQ<8>
  VSS49  = GND
  DQ9_B  = M_C_CPU0_SB_DQ<9>
  VSS50  = GND
  DQS1_B_T  = M_C_CPU0_SB_DQS_DP<1>
  DQS1_B_C  = M_C_CPU0_SB_DQS_DN<1>
  VSS51  = GND
  DQ12_B  = M_C_CPU0_SB_DQ<12>
  VSS52  = GND
  DQ13_B  = M_C_CPU0_SB_DQ<13>
  VSS53  = GND
  DQ16_B  = M_C_CPU0_SB_DQ<16>
  VSS54  = GND
  DQ17_B  = M_C_CPU0_SB_DQ<17>
  VSS55  = GND
  DQS2_B_T  = M_C_CPU0_SB_DQS_DP<2>
  DQS2_B_C  = M_C_CPU0_SB_DQS_DN<2>
  VSS56  = GND
  DQ20_B  = M_C_CPU0_SB_DQ<20>
  VSS57  = GND
  DQ21_B  = M_C_CPU0_SB_DQ<21>
  VSS58  = GND
  DQ24_B  = M_C_CPU0_SB_DQ<24>
  VSS59  = GND
  DQ25_B  = M_C_CPU0_SB_DQ<25>
  VSS60  = GND
  DQS3_B_T  = M_C_CPU0_SB_DQS_DP<3>
  DQS3_B_C  = M_C_CPU0_SB_DQS_DN<3>
  VSS61  = GND
  DQ28_B  = M_C_CPU0_SB_DQ<28>
  VSS62  = GND
  DQ29_B  = M_C_CPU0_SB_DQ<29>
  VSS63  = GND
  RFU1  = NC
  VIN_BULK1  = P12V_MEM_CPU0
  VIN_BULK2  = P12V_MEM_CPU0
  \pwr_good||fail_n\  = PWRGD_CHC_CPU0_DIMM
  HAS  = PD_CHC_CPU0_DIMM_SAA
  RFU2  = NC
  RFU3  = NC
  VSS64  = GND
  DQ2_A  = M_C_CPU0_SA_DQ<2>
  VSS65  = GND
  DQ3_A  = M_C_CPU0_SA_DQ<3>
  VSS66  = GND
  \dqs5_a_c||tdqs5_a_c||dqs5_a_t||tdqs5_a_t\  = M_C_CPU0_SA_DQS_DN<5>
  \dqs5_a_t||tdqs5_a_t\  = M_C_CPU0_SA_DQS_DP<5>
  VSS67  = GND
  DQ6_A  = M_C_CPU0_SA_DQ<6>
  VSS68  = GND
  DQ7_A  = M_C_CPU0_SA_DQ<7>
  VSS69  = GND
  DQ10_A  = M_C_CPU0_SA_DQ<10>
  VSS70  = GND
  DQ11_A  = M_C_CPU0_SA_DQ<11>
  VSS71  = GND
  \dqs6_a_c||tdqs6_a_c||dqs6_a_t||tdqs6_a_t\  = M_C_CPU0_SA_DQS_DN<6>
  \dqs6_a_t||tdqs6_a_t\  = M_C_CPU0_SA_DQS_DP<6>
  VSS72  = GND
  DQ14_A  = M_C_CPU0_SA_DQ<14>
  VSS73  = GND
  DQ15_A  = M_C_CPU0_SA_DQ<15>
  VSS74  = GND
  DQ18_A  = M_C_CPU0_SA_DQ<18>
  VSS75  = GND
  DQ19_A  = M_C_CPU0_SA_DQ<19>
  VSS76  = GND
  \dqs7_a_c||tdqs7_a_c\  = M_C_CPU0_SA_DQS_DN<7>
  \dqs7_a_t||tdqs7_a_t\  = M_C_CPU0_SA_DQS_DP<7>
  VSS77  = GND
  DQ22_A  = M_C_CPU0_SA_DQ<22>
  VSS78  = GND
  DQ23_A  = M_C_CPU0_SA_DQ<23>
  VSS79  = GND
  DQ26_A  = M_C_CPU0_SA_DQ<26>
  VSS80  = GND
  DQ27_A  = M_C_CPU0_SA_DQ<27>
  VSS81  = GND
  \dqs8_a_c||tdqs8_a_c\  = M_C_CPU0_SA_DQS_DN<8>
  \dqs8_a_t||tdqs8_a_t\  = M_C_CPU0_SA_DQS_DP<8>
  VSS82  = GND
  DQ30_A  = M_C_CPU0_SA_DQ<30>
  VSS83  = GND
  DQ31_A  = M_C_CPU0_SA_DQ<31>
  VSS84  = GND
  CB2_A  = M_C_CPU0_SA_CB<2>
  VSS85  = GND
  CB3_A  = M_C_CPU0_SA_CB<3>
  VSS86  = GND
  \dqs9_a_c||tdqs9_a_c\  = M_C_CPU0_SA_DQS_DN<9>
  \dqs9_a_t||tdqs9_a_t\  = M_C_CPU0_SA_DQS_DP<9>
  VSS87  = GND
  CB6_A  = M_C_CPU0_SA_CB<6>
  VSS88  = GND
  CB7_A  = M_C_CPU0_SA_CB<7>
  VSS89  = GND
  RESET_N  = M_C_CPU0_RESET_N
  VSS90  = GND
  CS1_A_N  = M_C_CPU0_SA_CS_N<1>
  VSS91  = GND
  CA1_A  = M_C_CPU0_SA_CA<1>
  VSS92  = GND
  CA3_A  = M_C_CPU0_SA_CA<3>
  VSS93  = GND
  CA5_A  = M_C_CPU0_SA_CA<5>
  VSS94  = GND
  CK_T  = M_C_CPU0_CLK_DP<0>
  CK_C  = M_C_CPU0_CLK_DN<0>
  VSS95  = GND
  RFU4  = NC
  CA1_B  = M_C_CPU0_SB_CA<1>
  VSS96  = GND
  CA3_B  = M_C_CPU0_SB_CA<3>
  VSS97  = GND
  CA5_B  = M_C_CPU0_SB_CA<5>
  VSS98  = GND
  PAR_B  = M_C_CPU0_SB_PAR
  VSS99  = GND
  CS1_B_N  = M_C_CPU0_SB_CS_N<1>
  VSS100  = GND
  RFU5  = NC
  RFU6  = NC
  VSS101  = GND
  CB6_B  = M_C_CPU0_SB_CB<6>
  VSS102  = GND
  CB7_B  = M_C_CPU0_SB_CB<7>
  VSS103  = GND
  DQS4_B_C  = M_C_CPU0_SB_DQS_DN<4>
  DQS4_B_T  = M_C_CPU0_SB_DQS_DP<4>
  VSS104  = GND
  CB2_B  = M_C_CPU0_SB_CB<2>
  VSS105  = GND
  CB3_B  = M_C_CPU0_SB_CB<3>
  VSS106  = GND
  DQ2_B  = M_C_CPU0_SB_DQ<2>
  VSS107  = GND
  DQ3_B  = M_C_CPU0_SB_DQ<3>
  VSS108  = GND
  \dqs5_b_c||tdqs5_b_c\  = M_C_CPU0_SB_DQS_DN<5>
  \dqs5_b_t||tdqs5_b_t\  = M_C_CPU0_SB_DQS_DP<5>
  VSS109  = GND
  DQ6_B  = M_C_CPU0_SB_DQ<6>
  VSS110  = GND
  DQ7_B  = M_C_CPU0_SB_DQ<7>
  VSS111  = GND
  DQ10_B  = M_C_CPU0_SB_DQ<10>
  VSS112  = GND
  DQ11_B  = M_C_CPU0_SB_DQ<11>
  VSS113  = GND
  \dqs6_b_c||tdqs6_b_c\  = M_C_CPU0_SB_DQS_DN<6>
  \dqs6_b_t||tdqs6_b_t\  = M_C_CPU0_SB_DQS_DP<6>
  VSS114  = GND
  DQ14_B  = M_C_CPU0_SB_DQ<14>
  VSS115  = GND
  DQ15_B  = M_C_CPU0_SB_DQ<15>
  VSS116  = GND
  DQ18_B  = M_C_CPU0_SB_DQ<18>
  VSS117  = GND
  DQ19_B  = M_C_CPU0_SB_DQ<19>
  VSS118  = GND
  \dqs7_b_c||tdqs7_b_c\  = M_C_CPU0_SB_DQS_DN<7>
  \dqs7_b_t||tdqs7_b_t\  = M_C_CPU0_SB_DQS_DP<7>
  VSS119  = GND
  DQ22_B  = M_C_CPU0_SB_DQ<22>
  VSS120  = GND
  DQ23_B  = M_C_CPU0_SB_DQ<23>
  VSS121  = GND
  DQ26_B  = M_C_CPU0_SB_DQ<26>
  VSS122  = GND
  DQ27_B  = M_C_CPU0_SB_DQ<27>
  VSS123  = GND
  \dqs8_b_c||tdqs8_b_c\  = M_C_CPU0_SB_DQS_DN<8>
  \dqs8_b_t||tdqs8_b_t\  = M_C_CPU0_SB_DQS_DP<8>
  VSS124  = GND
  DQ30_B  = M_C_CPU0_SB_DQ<30>
  VSS125  = GND
  DQ31_B  = M_C_CPU0_SB_DQ<31>
  VSS126  = GND
  G1  = GND
  G2  = GND
  G3  = GND

(kicad_pcb
	(version 20260206)
	(generator "pcbnew")
	(generator_version "10.0")
	(general
		(thickness 1.6)
		(legacy_teardrops no)
	)
	(paper "A4")
	(title_block
		(title "04192023_DAF0TMB3IC0_F0TG_MB_C_brd_V02_OCP.brd")
		(comment 1 "Grand Teton / footprint 4167 of 8354 (J17), pads 231-276 of 291")
	)
	(layers
		(0 "F.Cu" signal "TOP")
		(4 "In1.Cu" signal "GND")
		(6 "In2.Cu" signal "IN1")
		(8 "In3.Cu" signal "GND1")
		(10 "In4.Cu" signal "IN2")
		(12 "In5.Cu" signal "GND2")
		(14 "In6.Cu" signal "IN3")
		(16 "In7.Cu" signal "GND3")
		(18 "In8.Cu" signal "VCC")
		(20 "In9.Cu" signal "VCC1")
		(22 "In10.Cu" signal "GND4")
		(24 "In11.Cu" signal "IN4")
		(26 "In12.Cu" signal "GND5")
		(28 "In13.Cu" signal "IN5")
		(30 "In14.Cu" signal "GND6")
		(32 "In15.Cu" signal "IN6")
		(34 "In16.Cu" signal "GND7")
		(2 "B.Cu" signal "BOTTOM")
		(9 "F.Adhes" user "F.Adhesive")
		(11 "B.Adhes" user "B.Adhesive")
		(13 "F.Paste" user "Package Geometry/Pastemask Top")
		(15 "B.Paste" user "Package Geometry/Pastemask Bottom")
		(5 "F.SilkS" user "Ref Des/Silkscreen Top")
		(7 "B.SilkS" user "Ref Des/Silkscreen Bottom")
		(1 "F.Mask" user "Board Geometry/Soldermask Top")
		(3 "B.Mask" user "Board Geometry/Soldermask Bottom")
		(17 "Dwgs.User" user "User.Drawings")
		(19 "Cmts.User" user "User.Comments")
		(21 "Eco1.User" user "User.Eco1")
		(23 "Eco2.User" user "User.Eco2")
		(25 "Edge.Cuts" user "Board Geometry/Outline")
		(27 "Margin" user)
		(31 "F.CrtYd" user "Package Geometry/Place Bound Top")
		(29 "B.CrtYd" user "Package Geometry/Place Bound Bottom")
		(35 "F.Fab" user "Ref Des/Assembly Top")
		(33 "B.Fab" user "Ref Des/Assembly Bottom")
	)
	(footprint ""
		(layer "F.Cu")
		(at 290.230052 -255.560068 180)
		(property "Reference" "J17"
			(at -2.2098 -81.984088 0)
			(unlocked yes)
			(layer "F.SilkS")
			(effects
				(font
					(size 0.7874 0.5842)
					(thickness 0.1524)
				)
			)
		)
		(property "Value" ""
			(at 0 0 180)
			(layer "F.Fab")
			(effects
				(font
					(size 1.27 1.27)
				)
			)
		)
		(duplicate_pad_numbers_are_jumpers no)
		(pad "231" smd rect
			(at 2.050034 14.875002 90)
			(size 0.519938 1.4986)
			(layers "F.Cu" "F.Mask" "F.Paste")
			(net "Net_2282")
		)
		(pad "232" smd rect
			(at 2.050034 15.724886 90)
			(size 0.519938 1.4986)
			(layers "F.Cu" "F.Mask" "F.Paste")
			(net "Net_2283")
		)
		(pad "233" smd rect
			(at 2.050034 16.575024 90)
			(size 0.519938 1.4986)
			(layers "F.Cu" "F.Mask" "F.Paste")
			(net "GND")
		)
		(pad "234" smd rect
			(at 2.050034 17.424908 90)
			(size 0.519938 1.4986)
			(layers "F.Cu" "F.Mask" "F.Paste")
			(net "M_C_CPU0_SB_CB<6>")
		)
		(pad "235" smd rect
			(at 2.050034 18.275046 90)
			(size 0.519938 1.4986)
			(layers "F.Cu" "F.Mask" "F.Paste")
			(net "GND")
		)
		(pad "236" smd rect
			(at 2.050034 19.12493 90)
			(size 0.519938 1.4986)
			(layers "F.Cu" "F.Mask" "F.Paste")
			(net "M_C_CPU0_SB_CB<7>")
		)
		(pad "237" smd rect
			(at 2.050034 19.975068 90)
			(size 0.519938 1.4986)
			(layers "F.Cu" "F.Mask" "F.Paste")
			(net "GND")
		)
		(pad "238" smd rect
			(at 2.050034 20.824952 90)
			(size 0.519938 1.4986)
			(layers "F.Cu" "F.Mask" "F.Paste")
			(net "M_C_CPU0_SB_DQS_DN<4>")
		)
		(pad "239" smd rect
			(at 2.050034 21.67509 90)
			(size 0.519938 1.4986)
			(layers "F.Cu" "F.Mask" "F.Paste")
			(net "M_C_CPU0_SB_DQS_DP<4>")
		)
		(pad "240" smd rect
			(at 2.050034 22.524974 90)
			(size 0.519938 1.4986)
			(layers "F.Cu" "F.Mask" "F.Paste")
			(net "GND")
		)
		(pad "241" smd rect
			(at 2.050034 23.375112 90)
			(size 0.519938 1.4986)
			(layers "F.Cu" "F.Mask" "F.Paste")
			(net "M_C_CPU0_SB_CB<2>")
		)
		(pad "242" smd rect
			(at 2.050034 24.224996 90)
			(size 0.519938 1.4986)
			(layers "F.Cu" "F.Mask" "F.Paste")
			(net "GND")
		)
		(pad "243" smd rect
			(at 2.050034 25.07488 90)
			(size 0.519938 1.4986)
			(layers "F.Cu" "F.Mask" "F.Paste")
			(net "M_C_CPU0_SB_CB<3>")
		)
		(pad "244" smd rect
			(at 2.050034 25.925018 90)
			(size 0.519938 1.4986)
			(layers "F.Cu" "F.Mask" "F.Paste")
			(net "GND")
		)
		(pad "245" smd rect
			(at 2.050034 26.774902 90)
			(size 0.519938 1.4986)
			(layers "F.Cu" "F.Mask" "F.Paste")
			(net "M_C_CPU0_SB_DQ<2>")
		)
		(pad "246" smd rect
			(at 2.050034 27.62504 90)
			(size 0.519938 1.4986)
			(layers "F.Cu" "F.Mask" "F.Paste")
			(net "GND")
		)
		(pad "247" smd rect
			(at 2.050034 28.474924 90)
			(size 0.519938 1.4986)
			(layers "F.Cu" "F.Mask" "F.Paste")
			(net "M_C_CPU0_SB_DQ<3>")
		)
		(pad "248" smd rect
			(at 2.050034 29.325062 90)
			(size 0.519938 1.4986)
			(layers "F.Cu" "F.Mask" "F.Paste")
			(net "GND")
		)
		(pad "249" smd rect
			(at 2.050034 30.174946 90)
			(size 0.519938 1.4986)
			(layers "F.Cu" "F.Mask" "F.Paste")
			(net "M_C_CPU0_SB_DQS_DN<5>")
		)
		(pad "250" smd rect
			(at 2.050034 31.025084 90)
			(size 0.519938 1.4986)
			(layers "F.Cu" "F.Mask" "F.Paste")
			(net "M_C_CPU0_SB_DQS_DP<5>")
		)
		(pad "251" smd rect
			(at 2.050034 31.874968 90)
			(size 0.519938 1.4986)
			(layers "F.Cu" "F.Mask" "F.Paste")
			(net "GND")
		)
		(pad "252" smd rect
			(at 2.050034 32.725106 90)
			(size 0.519938 1.4986)
			(layers "F.Cu" "F.Mask" "F.Paste")
			(net "M_C_CPU0_SB_DQ<6>")
		)
		(pad "253" smd rect
			(at 2.050034 33.57499 90)
			(size 0.519938 1.4986)
			(layers "F.Cu" "F.Mask" "F.Paste")
			(net "GND")
		)
		(pad "254" smd rect
			(at 2.050034 34.425128 90)
			(size 0.519938 1.4986)
			(layers "F.Cu" "F.Mask" "F.Paste")
			(net "M_C_CPU0_SB_DQ<7>")
		)
		(pad "255" smd rect
			(at 2.050034 35.275012 90)
			(size 0.519938 1.4986)
			(layers "F.Cu" "F.Mask" "F.Paste")
			(net "GND")
		)
		(pad "256" smd rect
			(at 2.050034 36.124896 90)
			(size 0.519938 1.4986)
			(layers "F.Cu" "F.Mask" "F.Paste")
			(net "M_C_CPU0_SB_DQ<10>")
		)
		(pad "257" smd rect
			(at 2.050034 36.975034 90)
			(size 0.519938 1.4986)
			(layers "F.Cu" "F.Mask" "F.Paste")
			(net "GND")
		)
		(pad "258" smd rect
			(at 2.050034 37.824918 90)
			(size 0.519938 1.4986)
			(layers "F.Cu" "F.Mask" "F.Paste")
			(net "M_C_CPU0_SB_DQ<11>")
		)
		(pad "259" smd rect
			(at 2.050034 38.675056 90)
			(size 0.519938 1.4986)
			(layers "F.Cu" "F.Mask" "F.Paste")
			(net "GND")
		)
		(pad "260" smd rect
			(at 2.050034 39.52494 90)
			(size 0.519938 1.4986)
			(layers "F.Cu" "F.Mask" "F.Paste")
			(net "M_C_CPU0_SB_DQS_DN<6>")
		)
		(pad "261" smd rect
			(at 2.050034 40.375078 90)
			(size 0.519938 1.4986)
			(layers "F.Cu" "F.Mask" "F.Paste")
			(net "M_C_CPU0_SB_DQS_DP<6>")
		)
		(pad "262" smd rect
			(at 2.050034 41.224962 90)
			(size 0.519938 1.4986)
			(layers "F.Cu" "F.Mask" "F.Paste")
			(net "GND")
		)
		(pad "263" smd rect
			(at 2.050034 42.0751 90)
			(size 0.519938 1.4986)
			(layers "F.Cu" "F.Mask" "F.Paste")
			(net "M_C_CPU0_SB_DQ<14>")
		)
		(pad "264" smd rect
			(at 2.050034 42.924984 90)
			(size 0.519938 1.4986)
			(layers "F.Cu" "F.Mask" "F.Paste")
			(net "GND")
		)
		(pad "265" smd rect
			(at 2.050034 43.775122 90)
			(size 0.519938 1.4986)
			(layers "F.Cu" "F.Mask" "F.Paste")
			(net "M_C_CPU0_SB_DQ<15>")
		)
		(pad "266" smd rect
			(at 2.050034 44.625006 90)
			(size 0.519938 1.4986)
			(layers "F.Cu" "F.Mask" "F.Paste")
			(net "GND")
		)
		(pad "267" smd rect
			(at 2.050034 45.47489 90)
			(size 0.519938 1.4986)
			(layers "F.Cu" "F.Mask" "F.Paste")
			(net "M_C_CPU0_SB_DQ<18>")
		)
		(pad "268" smd rect
			(at 2.050034 46.325028 90)
			(size 0.519938 1.4986)
			(layers "F.Cu" "F.Mask" "F.Paste")
			(net "GND")
		)
		(pad "269" smd rect
			(at 2.050034 47.174912 90)
			(size 0.519938 1.4986)
			(layers "F.Cu" "F.Mask" "F.Paste")
			(net "M_C_CPU0_SB_DQ<19>")
		)
		(pad "270" smd rect
			(at 2.050034 48.02505 90)
			(size 0.519938 1.4986)
			(layers "F.Cu" "F.Mask" "F.Paste")
			(net "GND")
		)
		(pad "271" smd rect
			(at 2.050034 48.874934 90)
			(size 0.519938 1.4986)
			(layers "F.Cu" "F.Mask" "F.Paste")
			(net "M_C_CPU0_SB_DQS_DN<7>")
		)
		(pad "272" smd rect
			(at 2.050034 49.725072 90)
			(size 0.519938 1.4986)
			(layers "F.Cu" "F.Mask" "F.Paste")
			(net "M_C_CPU0_SB_DQS_DP<7>")
		)
		(pad "273" smd rect
			(at 2.050034 50.574956 90)
			(size 0.519938 1.4986)
			(layers "F.Cu" "F.Mask" "F.Paste")
			(net "GND")
		)
		(pad "274" smd rect
			(at 2.050034 51.425094 90)
			(size 0.519938 1.4986)
			(layers "F.Cu" "F.Mask" "F.Paste")
			(net "M_C_CPU0_SB_DQ<22>")
		)
		(pad "275" smd rect
			(at 2.050034 52.274978 90)
			(size 0.519938 1.4986)
			(layers "F.Cu" "F.Mask" "F.Paste")
			(net "GND")
		)
		(pad "276" smd rect
			(at 2.050034 53.125116 90)
			(size 0.519938 1.4986)
			(layers "F.Cu" "F.Mask" "F.Paste")
			(net "M_C_CPU0_SB_DQ<23>")
		)
	)
)
